(kicad_pcb
	(version 20260206)
	(generator "pcbnew")
	(generator_version "10.0")
	(general
		(thickness 1.6)
		(legacy_teardrops no)
	)
	(paper "A4")
	(title_block
		(title "04192023_DAF0TMB3IC0_F0TG_MB_C_brd_V02_OCP.brd")
		(comment 1 "Grand Teton / footprints 4162-4166 of 8354")
	)
	(layers
		(0 "F.Cu" signal "TOP")
		(4 "In1.Cu" signal "GND")
		(6 "In2.Cu" signal "IN1")
		(8 "In3.Cu" signal "GND1")
		(10 "In4.Cu" signal "IN2")
		(12 "In5.Cu" signal "GND2")
		(14 "In6.Cu" signal "IN3")
		(16 "In7.Cu" signal "GND3")
		(18 "In8.Cu" signal "VCC")
		(20 "In9.Cu" signal "VCC1")
		(22 "In10.Cu" signal "GND4")
		(24 "In11.Cu" signal "IN4")
		(26 "In12.Cu" signal "GND5")
		(28 "In13.Cu" signal "IN5")
		(30 "In14.Cu" signal "GND6")
		(32 "In15.Cu" signal "IN6")
		(34 "In16.Cu" signal "GND7")
		(2 "B.Cu" signal "BOTTOM")
		(9 "F.Adhes" user "F.Adhesive")
		(11 "B.Adhes" user "B.Adhesive")
		(13 "F.Paste" user "Package Geometry/Pastemask Top")
		(15 "B.Paste" user "Package Geometry/Pastemask Bottom")
		(5 "F.SilkS" user "Ref Des/Silkscreen Top")
		(7 "B.SilkS" user "Ref Des/Silkscreen Bottom")
		(1 "F.Mask" user "Board Geometry/Soldermask Top")
		(3 "B.Mask" user "Board Geometry/Soldermask Bottom")
		(17 "Dwgs.User" user "User.Drawings")
		(19 "Cmts.User" user "User.Comments")
		(21 "Eco1.User" user "User.Eco1")
		(23 "Eco2.User" user "User.Eco2")
		(25 "Edge.Cuts" user "Board Geometry/Outline")
		(27 "Margin" user)
		(31 "F.CrtYd" user "Package Geometry/Place Bound Top")
		(29 "B.CrtYd" user "Package Geometry/Place Bound Bottom")
		(35 "F.Fab" user "Ref Des/Assembly Top")
		(33 "B.Fab" user "Ref Des/Assembly Bottom")
	)
	(footprint ""
		(layer "F.Cu")
		(at 163.4236 -436.153052)
		(property "Reference" "R3438"
			(at 0 0 0)
			(layer "F.SilkS")
			(hide yes)
			(effects
				(font
					(size 1.27 1.27)
				)
			)
		)
		(property "Value" ""
			(at 0 0 0)
			(layer "F.Fab")
			(effects
				(font
					(size 1.27 1.27)
				)
			)
		)
		(duplicate_pad_numbers_are_jumpers no)
		(fp_line
			(start -0.7874 -0.4064)
			(end 0.7874 -0.4064)
			(stroke
				(width 0.1524)
				(type default)
			)
			(layer "F.SilkS")
		)
		(fp_line
			(start -0.7874 0.4064)
			(end -0.7874 -0.4064)
			(stroke
				(width 0.1524)
				(type default)
			)
			(layer "F.SilkS")
		)
		(fp_line
			(start 0.7874 -0.4064)
			(end 0.7874 0.4064)
			(stroke
				(width 0.1524)
				(type default)
			)
			(layer "F.SilkS")
		)
		(fp_line
			(start 0.7874 0.4064)
			(end -0.7874 0.4064)
			(stroke
				(width 0.1524)
				(type default)
			)
			(layer "F.SilkS")
		)
		(fp_line
			(start -0.67945 -0.305054)
			(end -0.12065 -0.305054)
			(stroke
				(width 0.1)
				(type default)
			)
			(layer "F.Fab")
		)
		(fp_line
			(start -0.67945 0.3048)
			(end -0.67945 -0.305054)
			(stroke
				(width 0.1)
				(type default)
			)
			(layer "F.Fab")
		)
		(fp_line
			(start -0.12065 -0.305054)
			(end -0.12065 -0.2794)
			(stroke
				(width 0.1)
				(type default)
			)
			(layer "F.Fab")
		)
		(fp_line
			(start -0.12065 -0.2794)
			(end 0.12065 -0.2794)
			(stroke
				(width 0.1)
				(type default)
			)
			(layer "F.Fab")
		)
		(fp_line
			(start -0.12065 0.2794)
			(end -0.12065 0.3048)
			(stroke
				(width 0.1)
				(type default)
			)
			(layer "F.Fab")
		)
		(fp_line
			(start -0.12065 0.3048)
			(end -0.67945 0.3048)
			(stroke
				(width 0.1)
				(type default)
			)
			(layer "F.Fab")
		)
		(fp_line
			(start 0.120396 0.2794)
			(end -0.12065 0.2794)
			(stroke
				(width 0.1)
				(type default)
			)
			(layer "F.Fab")
		)
		(fp_line
			(start 0.120396 0.3048)
			(end 0.120396 0.2794)
			(stroke
				(width 0.1)
				(type default)
			)
			(layer "F.Fab")
		)
		(fp_line
			(start 0.12065 -0.3048)
			(end 0.67945 -0.3048)
			(stroke
				(width 0.1)
				(type default)
			)
			(layer "F.Fab")
		)
		(fp_line
			(start 0.12065 -0.2794)
			(end 0.12065 -0.3048)
			(stroke
				(width 0.1)
				(type default)
			)
			(layer "F.Fab")
		)
		(fp_line
			(start 0.67945 -0.3048)
			(end 0.67945 0.3048)
			(stroke
				(width 0.1)
				(type default)
			)
			(layer "F.Fab")
		)
		(fp_line
			(start 0.67945 0.3048)
			(end 0.120396 0.3048)
			(stroke
				(width 0.1)
				(type default)
			)
			(layer "F.Fab")
		)
		(pad "1" smd circle
			(at -0.40005 0)
			(size 0 0)
			(layers "F.Cu" "F.Mask" "F.Paste")
			(net "P3V3_AUX")
		)
		(pad "2" smd circle
			(at 0.40005 0)
			(size 0 0)
			(layers "F.Cu" "F.Mask" "F.Paste")
			(net "GPU_BASE_HMC_READY_ISO")
		)
	)
	(footprint ""
		(layer "F.Cu")
		(at 197.269608 -117.689376)
		(property "Reference" "R685"
			(at 0 0 0)
			(layer "F.SilkS")
			(hide yes)
			(effects
				(font
					(size 1.27 1.27)
				)
			)
		)
		(property "Value" ""
			(at 0 0 0)
			(layer "F.Fab")
			(effects
				(font
					(size 1.27 1.27)
				)
			)
		)
		(duplicate_pad_numbers_are_jumpers no)
		(fp_line
			(start -0.7874 -0.4064)
			(end 0.7874 -0.4064)
			(stroke
				(width 0.1524)
				(type default)
			)
			(layer "F.SilkS")
		)
		(fp_line
			(start -0.7874 0.4064)
			(end -0.7874 -0.4064)
			(stroke
				(width 0.1524)
				(type default)
			)
			(layer "F.SilkS")
		)
		(fp_line
			(start 0.7874 -0.4064)
			(end 0.7874 0.4064)
			(stroke
				(width 0.1524)
				(type default)
			)
			(layer "F.SilkS")
		)
		(fp_line
			(start 0.7874 0.4064)
			(end -0.7874 0.4064)
			(stroke
				(width 0.1524)
				(type default)
			)
			(layer "F.SilkS")
		)
		(fp_line
			(start -0.67945 -0.305054)
			(end -0.12065 -0.305054)
			(stroke
				(width 0.1)
				(type default)
			)
			(layer "F.Fab")
		)
		(fp_line
			(start -0.67945 0.3048)
			(end -0.67945 -0.305054)
			(stroke
				(width 0.1)
				(type default)
			)
			(layer "F.Fab")
		)
		(fp_line
			(start -0.12065 -0.305054)
			(end -0.12065 -0.2794)
			(stroke
				(width 0.1)
				(type default)
			)
			(layer "F.Fab")
		)
		(fp_line
			(start -0.12065 -0.2794)
			(end 0.12065 -0.2794)
			(stroke
				(width 0.1)
				(type default)
			)
			(layer "F.Fab")
		)
		(fp_line
			(start -0.12065 0.2794)
			(end -0.12065 0.3048)
			(stroke
				(width 0.1)
				(type default)
			)
			(layer "F.Fab")
		)
		(fp_line
			(start -0.12065 0.3048)
			(end -0.67945 0.3048)
			(stroke
				(width 0.1)
				(type default)
			)
			(layer "F.Fab")
		)
		(fp_line
			(start 0.120396 0.2794)
			(end -0.12065 0.2794)
			(stroke
				(width 0.1)
				(type default)
			)
			(layer "F.Fab")
		)
		(fp_line
			(start 0.120396 0.3048)
			(end 0.120396 0.2794)
			(stroke
				(width 0.1)
				(type default)
			)
			(layer "F.Fab")
		)
		(fp_line
			(start 0.12065 -0.3048)
			(end 0.67945 -0.3048)
			(stroke
				(width 0.1)
				(type default)
			)
			(layer "F.Fab")
		)
		(fp_line
			(start 0.12065 -0.2794)
			(end 0.12065 -0.3048)
			(stroke
				(width 0.1)
				(type default)
			)
			(layer "F.Fab")
		)
		(fp_line
			(start 0.67945 -0.3048)
			(end 0.67945 0.3048)
			(stroke
				(width 0.1)
				(type default)
			)
			(layer "F.Fab")
		)
		(fp_line
			(start 0.67945 0.3048)
			(end 0.120396 0.3048)
			(stroke
				(width 0.1)
				(type default)
			)
			(layer "F.Fab")
		)
		(pad "1" smd circle
			(at -0.40005 0)
			(size 0 0)
			(layers "F.Cu" "F.Mask" "F.Paste")
			(net "RST_PERST_E1S_0_R_N")
		)
		(pad "2" smd circle
			(at 0.40005 0)
			(size 0 0)
			(layers "F.Cu" "F.Mask" "F.Paste")
			(net "RST_PERST_E1S_0_N")
		)
	)
	(footprint ""
		(layer "F.Cu")
		(at 126.111 -321.655948 90)
		(property "Reference" "R3352"
			(at 0 0 90)
			(layer "F.SilkS")
			(hide yes)
			(effects
				(font
					(size 1.27 1.27)
				)
			)
		)
		(property "Value" ""
			(at 0 0 90)
			(layer "F.Fab")
			(effects
				(font
					(size 1.27 1.27)
				)
			)
		)
		(duplicate_pad_numbers_are_jumpers no)
		(fp_line
			(start -0.371348 -0.4064)
			(end 0.390652 -0.4064)
			(stroke
				(width 0.1524)
				(type default)
			)
			(layer "F.SilkS")
		)
		(fp_line
			(start 0.7874 0)
			(end 0.7874 0.4064)
			(stroke
				(width 0.1524)
				(type default)
			)
			(layer "F.SilkS")
		)
		(fp_line
			(start 0.7874 0.4064)
			(end -0.7874 0.4064)
			(stroke
				(width 0.1524)
				(type default)
			)
			(layer "F.SilkS")
		)
		(fp_line
			(start -0.7874 0.4064)
			(end -0.7874 0.0254)
			(stroke
				(width 0.1524)
				(type default)
			)
			(layer "F.SilkS")
		)
		(fp_line
			(start -0.12065 -0.305054)
			(end -0.12065 -0.2794)
			(stroke
				(width 0.1)
				(type default)
			)
			(layer "F.Fab")
		)
		(fp_line
			(start -0.67945 -0.305054)
			(end -0.12065 -0.305054)
			(stroke
				(width 0.1)
				(type default)
			)
			(layer "F.Fab")
		)
		(fp_line
			(start 0.67945 -0.3048)
			(end 0.67945 0.3048)
			(stroke
				(width 0.1)
				(type default)
			)
			(layer "F.Fab")
		)
		(fp_line
			(start 0.12065 -0.3048)
			(end 0.67945 -0.3048)
			(stroke
				(width 0.1)
				(type default)
			)
			(layer "F.Fab")
		)
		(fp_line
			(start 0.12065 -0.2794)
			(end 0.12065 -0.3048)
			(stroke
				(width 0.1)
				(type default)
			)
			(layer "F.Fab")
		)
		(fp_line
			(start -0.12065 -0.2794)
			(end 0.12065 -0.2794)
			(stroke
				(width 0.1)
				(type default)
			)
			(layer "F.Fab")
		)
		(fp_line
			(start 0.120396 0.2794)
			(end -0.12065 0.2794)
			(stroke
				(width 0.1)
				(type default)
			)
			(layer "F.Fab")
		)
		(fp_line
			(start -0.12065 0.2794)
			(end -0.12065 0.3048)
			(stroke
				(width 0.1)
				(type default)
			)
			(layer "F.Fab")
		)
		(fp_line
			(start 0.67945 0.3048)
			(end 0.120396 0.3048)
			(stroke
				(width 0.1)
				(type default)
			)
			(layer "F.Fab")
		)
		(fp_line
			(start 0.120396 0.3048)
			(end 0.120396 0.2794)
			(stroke
				(width 0.1)
				(type default)
			)
			(layer "F.Fab")
		)
		(fp_line
			(start -0.12065 0.3048)
			(end -0.67945 0.3048)
			(stroke
				(width 0.1)
				(type default)
			)
			(layer "F.Fab")
		)
		(fp_line
			(start -0.67945 0.3048)
			(end -0.67945 -0.305054)
			(stroke
				(width 0.1)
				(type default)
			)
			(layer "F.Fab")
		)
		(pad "1" smd circle
			(at -0.40005 0 90)
			(size 0 0)
			(layers "F.Cu" "F.Mask" "F.Paste")
			(net "CLK_100M_CPU1_CLK11_R_DP")
		)
		(pad "2" smd circle
			(at 0.40005 0 90)
			(size 0 0)
			(layers "F.Cu" "F.Mask" "F.Paste")
			(net "CLK_100M_CPU1_CLK11_DP")
		)
	)
	(footprint ""
		(layer "F.Cu")
		(at 167.132 -109.184948 180)
		(property "Reference" "R6096"
			(at 0 0 180)
			(layer "F.SilkS")
			(hide yes)
			(effects
				(font
					(size 1.27 1.27)
				)
			)
		)
		(property "Value" ""
			(at 0 0 180)
			(layer "F.Fab")
			(effects
				(font
					(size 1.27 1.27)
				)
			)
		)
		(duplicate_pad_numbers_are_jumpers no)
		(fp_line
			(start 0.7874 0.4064)
			(end -0.7874 0.4064)
			(stroke
				(width 0.1524)
				(type default)
			)
			(layer "F.SilkS")
		)
		(fp_line
			(start 0.7874 -0.4064)
			(end 0.7874 0.4064)
			(stroke
				(width 0.1524)
				(type default)
			)
			(layer "F.SilkS")
		)
		(fp_line
			(start -0.7874 0.4064)
			(end -0.7874 -0.4064)
			(stroke
				(width 0.1524)
				(type default)
			)
			(layer "F.SilkS")
		)
		(fp_line
			(start -0.7874 -0.4064)
			(end 0.7874 -0.4064)
			(stroke
				(width 0.1524)
				(type default)
			)
			(layer "F.SilkS")
		)
		(fp_line
			(start 0.67945 0.3048)
			(end 0.120396 0.3048)
			(stroke
				(width 0.1)
				(type default)
			)
			(layer "F.Fab")
		)
		(fp_line
			(start 0.67945 -0.3048)
			(end 0.67945 0.3048)
			(stroke
				(width 0.1)
				(type default)
			)
			(layer "F.Fab")
		)
		(fp_line
			(start 0.12065 -0.2794)
			(end 0.12065 -0.3048)
			(stroke
				(width 0.1)
				(type default)
			)
			(layer "F.Fab")
		)
		(fp_line
			(start 0.12065 -0.3048)
			(end 0.67945 -0.3048)
			(stroke
				(width 0.1)
				(type default)
			)
			(layer "F.Fab")
		)
		(fp_line
			(start 0.120396 0.3048)
			(end 0.120396 0.2794)
			(stroke
				(width 0.1)
				(type default)
			)
			(layer "F.Fab")
		)
		(fp_line
			(start 0.120396 0.2794)
			(end -0.12065 0.2794)
			(stroke
				(width 0.1)
				(type default)
			)
			(layer "F.Fab")
		)
		(fp_line
			(start -0.12065 0.3048)
			(end -0.67945 0.3048)
			(stroke
				(width 0.1)
				(type default)
			)
			(layer "F.Fab")
		)
		(fp_line
			(start -0.12065 0.2794)
			(end -0.12065 0.3048)
			(stroke
				(width 0.1)
				(type default)
			)
			(layer "F.Fab")
		)
		(fp_line
			(start -0.12065 -0.2794)
			(end 0.12065 -0.2794)
			(stroke
				(width 0.1)
				(type default)
			)
			(layer "F.Fab")
		)
		(fp_line
			(start -0.12065 -0.305054)
			(end -0.12065 -0.2794)
			(stroke
				(width 0.1)
				(type default)
			)
			(layer "F.Fab")
		)
		(fp_line
			(start -0.67945 0.3048)
			(end -0.67945 -0.305054)
			(stroke
				(width 0.1)
				(type default)
			)
			(layer "F.Fab")
		)
		(fp_line
			(start -0.67945 -0.305054)
			(end -0.12065 -0.305054)
			(stroke
				(width 0.1)
				(type default)
			)
			(layer "F.Fab")
		)
		(pad "1" smd circle
			(at -0.40005 0 180)
			(size 0 0)
			(layers "F.Cu" "F.Mask" "F.Paste")
			(net "FM_UV_ADR_TRIGGER_R_N")
		)
		(pad "2" smd circle
			(at 0.40005 0 180)
			(size 0 0)
			(layers "F.Cu" "F.Mask" "F.Paste")
			(net "FM_UV_ADR_TRIGGER_N")
		)
	)
	(footprint ""
		(layer "F.Cu")
		(at 69.862446 -385.09448 180)
		(property "Reference" "R6702"
			(at 0 0 180)
			(layer "F.SilkS")
			(hide yes)
			(effects
				(font
					(size 1.27 1.27)
				)
			)
		)
		(property "Value" ""
			(at 0 0 180)
			(layer "F.Fab")
			(effects
				(font
					(size 1.27 1.27)
				)
			)
		)
		(duplicate_pad_numbers_are_jumpers no)
		(fp_line
			(start 0.7874 0.4064)
			(end -0.7874 0.4064)
			(stroke
				(width 0.1524)
				(type default)
			)
			(layer "F.SilkS")
		)
		(fp_line
			(start 0.7874 -0.4064)
			(end 0.7874 0.4064)
			(stroke
				(width 0.1524)
				(type default)
			)
			(layer "F.SilkS")
		)
		(fp_line
			(start -0.7874 0.4064)
			(end -0.7874 -0.4064)
			(stroke
				(width 0.1524)
				(type default)
			)
			(layer "F.SilkS")
		)
		(fp_line
			(start -0.7874 -0.4064)
			(end 0.7874 -0.4064)
			(stroke
				(width 0.1524)
				(type default)
			)
			(layer "F.SilkS")
		)
		(fp_line
			(start 0.67945 0.3048)
			(end 0.120396 0.3048)
			(stroke
				(width 0.1)
				(type default)
			)
			(layer "F.Fab")
		)
		(fp_line
			(start 0.67945 -0.3048)
			(end 0.67945 0.3048)
			(stroke
				(width 0.1)
				(type default)
			)
			(layer "F.Fab")
		)
		(fp_line
			(start 0.12065 -0.2794)
			(end 0.12065 -0.3048)
			(stroke
				(width 0.1)
				(type default)
			)
			(layer "F.Fab")
		)
		(fp_line
			(start 0.12065 -0.3048)
			(end 0.67945 -0.3048)
			(stroke
				(width 0.1)
				(type default)
			)
			(layer "F.Fab")
		)
		(fp_line
			(start 0.120396 0.3048)
			(end 0.120396 0.2794)
			(stroke
				(width 0.1)
				(type default)
			)
			(layer "F.Fab")
		)
		(fp_line
			(start 0.120396 0.2794)
			(end -0.12065 0.2794)
			(stroke
				(width 0.1)
				(type default)
			)
			(layer "F.Fab")
		)
		(fp_line
			(start -0.12065 0.3048)
			(end -0.67945 0.3048)
			(stroke
				(width 0.1)
				(type default)
			)
			(layer "F.Fab")
		)
		(fp_line
			(start -0.12065 0.2794)
			(end -0.12065 0.3048)
			(stroke
				(width 0.1)
				(type default)
			)
			(layer "F.Fab")
		)
		(fp_line
			(start -0.12065 -0.2794)
			(end 0.12065 -0.2794)
			(stroke
				(width 0.1)
				(type default)
			)
			(layer "F.Fab")
		)
		(fp_line
			(start -0.12065 -0.305054)
			(end -0.12065 -0.2794)
			(stroke
				(width 0.1)
				(type default)
			)
			(layer "F.Fab")
		)
		(fp_line
			(start -0.67945 0.3048)
			(end -0.67945 -0.305054)
			(stroke
				(width 0.1)
				(type default)
			)
			(layer "F.Fab")
		)
		(fp_line
			(start -0.67945 -0.305054)
			(end -0.12065 -0.305054)
			(stroke
				(width 0.1)
				(type default)
			)
			(layer "F.Fab")
		)
		(pad "1" smd rect
			(at -0.40005 0)
			(size 0.4572 0.508)
			(layers "F.Cu" "F.Mask" "F.Paste")
			(net "P1V8_CPU1_RT0_1A_1D")
		)
		(pad "2" smd rect
			(at 0.40005 0)
			(size 0.4572 0.508)
			(layers "F.Cu" "F.Mask" "F.Paste")
			(net "P1V8_CPU1_RT0_1A")
		)
	)
)
